(kicad_pcb
	(version 20260206)
	(generator "pcbnew")
	(generator_version "10.0")
	(general
		(thickness 1.6)
		(legacy_teardrops no)
	)
	(paper "A4")
	(title_block
		(title "04192023_DAF0TMB3IC0_F0TG_MB_C_brd_V02_OCP.brd")
		(comment 1 "Grand Teton / footprints 2983-2988 of 8354")
	)
	(layers
		(0 "F.Cu" signal "TOP")
		(4 "In1.Cu" signal "GND")
		(6 "In2.Cu" signal "IN1")
		(8 "In3.Cu" signal "GND1")
		(10 "In4.Cu" signal "IN2")
		(12 "In5.Cu" signal "GND2")
		(14 "In6.Cu" signal "IN3")
		(16 "In7.Cu" signal "GND3")
		(18 "In8.Cu" signal "VCC")
		(20 "In9.Cu" signal "VCC1")
		(22 "In10.Cu" signal "GND4")
		(24 "In11.Cu" signal "IN4")
		(26 "In12.Cu" signal "GND5")
		(28 "In13.Cu" signal "IN5")
		(30 "In14.Cu" signal "GND6")
		(32 "In15.Cu" signal "IN6")
		(34 "In16.Cu" signal "GND7")
		(2 "B.Cu" signal "BOTTOM")
		(9 "F.Adhes" user "F.Adhesive")
		(11 "B.Adhes" user "B.Adhesive")
		(13 "F.Paste" user "Package Geometry/Pastemask Top")
		(15 "B.Paste" user "Package Geometry/Pastemask Bottom")
		(5 "F.SilkS" user "Ref Des/Silkscreen Top")
		(7 "B.SilkS" user "Ref Des/Silkscreen Bottom")
		(1 "F.Mask" user "Board Geometry/Soldermask Top")
		(3 "B.Mask" user "Board Geometry/Soldermask Bottom")
		(17 "Dwgs.User" user "User.Drawings")
		(19 "Cmts.User" user "User.Comments")
		(21 "Eco1.User" user "User.Eco1")
		(23 "Eco2.User" user "User.Eco2")
		(25 "Edge.Cuts" user "Board Geometry/Outline")
		(27 "Margin" user)
		(31 "F.CrtYd" user "Package Geometry/Place Bound Top")
		(29 "B.CrtYd" user "Package Geometry/Place Bound Bottom")
		(35 "F.Fab" user "Ref Des/Assembly Top")
		(33 "B.Fab" user "Ref Des/Assembly Bottom")
	)
	(footprint ""
		(layer "F.Cu")
		(at 35.57651 -351.932748)
		(property "Reference" "PR369"
			(at 0 0 0)
			(layer "F.SilkS")
			(hide yes)
			(effects
				(font
					(size 1.27 1.27)
				)
			)
		)
		(property "Value" ""
			(at 0 0 0)
			(layer "F.Fab")
			(effects
				(font
					(size 1.27 1.27)
				)
			)
		)
		(duplicate_pad_numbers_are_jumpers no)
		(fp_line
			(start -0.7874 -0.4064)
			(end 0.7874 -0.4064)
			(stroke
				(width 0.1524)
				(type default)
			)
			(layer "F.SilkS")
		)
		(fp_line
			(start -0.7874 0.4064)
			(end -0.7874 -0.4064)
			(stroke
				(width 0.1524)
				(type default)
			)
			(layer "F.SilkS")
		)
		(fp_line
			(start 0.7874 -0.4064)
			(end 0.7874 0.4064)
			(stroke
				(width 0.1524)
				(type default)
			)
			(layer "F.SilkS")
		)
		(fp_line
			(start 0.7874 0.4064)
			(end -0.7874 0.4064)
			(stroke
				(width 0.1524)
				(type default)
			)
			(layer "F.SilkS")
		)
		(fp_line
			(start -0.67945 -0.305054)
			(end -0.12065 -0.305054)
			(stroke
				(width 0.1)
				(type default)
			)
			(layer "F.Fab")
		)
		(fp_line
			(start -0.67945 0.3048)
			(end -0.67945 -0.305054)
			(stroke
				(width 0.1)
				(type default)
			)
			(layer "F.Fab")
		)
		(fp_line
			(start -0.12065 -0.305054)
			(end -0.12065 -0.2794)
			(stroke
				(width 0.1)
				(type default)
			)
			(layer "F.Fab")
		)
		(fp_line
			(start -0.12065 -0.2794)
			(end 0.12065 -0.2794)
			(stroke
				(width 0.1)
				(type default)
			)
			(layer "F.Fab")
		)
		(fp_line
			(start -0.12065 0.2794)
			(end -0.12065 0.3048)
			(stroke
				(width 0.1)
				(type default)
			)
			(layer "F.Fab")
		)
		(fp_line
			(start -0.12065 0.3048)
			(end -0.67945 0.3048)
			(stroke
				(width 0.1)
				(type default)
			)
			(layer "F.Fab")
		)
		(fp_line
			(start 0.120396 0.2794)
			(end -0.12065 0.2794)
			(stroke
				(width 0.1)
				(type default)
			)
			(layer "F.Fab")
		)
		(fp_line
			(start 0.120396 0.3048)
			(end 0.120396 0.2794)
			(stroke
				(width 0.1)
				(type default)
			)
			(layer "F.Fab")
		)
		(fp_line
			(start 0.12065 -0.3048)
			(end 0.67945 -0.3048)
			(stroke
				(width 0.1)
				(type default)
			)
			(layer "F.Fab")
		)
		(fp_line
			(start 0.12065 -0.2794)
			(end 0.12065 -0.3048)
			(stroke
				(width 0.1)
				(type default)
			)
			(layer "F.Fab")
		)
		(fp_line
			(start 0.67945 -0.3048)
			(end 0.67945 0.3048)
			(stroke
				(width 0.1)
				(type default)
			)
			(layer "F.Fab")
		)
		(fp_line
			(start 0.67945 0.3048)
			(end 0.120396 0.3048)
			(stroke
				(width 0.1)
				(type default)
			)
			(layer "F.Fab")
		)
		(pad "1" smd circle
			(at -0.40005 0)
			(size 0 0)
			(layers "F.Cu" "F.Mask" "F.Paste")
			(net "PVDDIO_P1_LSET3")
		)
		(pad "2" smd circle
			(at 0.40005 0)
			(size 0 0)
			(layers "F.Cu" "F.Mask" "F.Paste")
			(net "GND")
		)
	)
	(footprint ""
		(layer "F.Cu")
		(at 209.622136 -142.582138)
		(property "Reference" "Q54"
			(at -1.651 -2.25933 0)
			(unlocked yes)
			(layer "F.SilkS")
			(effects
				(font
					(size 0.7874 0.5842)
					(thickness 0.1524)
				)
				(justify left)
			)
		)
		(property "Value" ""
			(at 0 0 0)
			(layer "F.Fab")
			(effects
				(font
					(size 1.27 1.27)
				)
			)
		)
		(duplicate_pad_numbers_are_jumpers no)
		(fp_line
			(start -1.603248 -1.500124)
			(end 1.603248 -1.500124)
			(stroke
				(width 0.1524)
				(type default)
			)
			(layer "F.SilkS")
		)
		(fp_line
			(start -1.603248 1.500124)
			(end -1.603248 -1.500124)
			(stroke
				(width 0.1524)
				(type default)
			)
			(layer "F.SilkS")
		)
		(fp_line
			(start 1.603248 -1.500124)
			(end 1.603248 1.500124)
			(stroke
				(width 0.1524)
				(type default)
			)
			(layer "F.SilkS")
		)
		(fp_line
			(start 1.603248 1.500124)
			(end -1.603248 1.500124)
			(stroke
				(width 0.1524)
				(type default)
			)
			(layer "F.SilkS")
		)
		(fp_line
			(start -1.249934 -1.169924)
			(end -1.249934 -0.729996)
			(stroke
				(width 0.1)
				(type default)
			)
			(layer "F.Fab")
		)
		(fp_line
			(start -1.249934 -0.729996)
			(end -0.6985 -0.729996)
			(stroke
				(width 0.1)
				(type default)
			)
			(layer "F.Fab")
		)
		(fp_line
			(start -1.249934 0.729996)
			(end -1.249934 1.169924)
			(stroke
				(width 0.1)
				(type default)
			)
			(layer "F.Fab")
		)
		(fp_line
			(start -1.249934 1.169924)
			(end -0.700024 1.169924)
			(stroke
				(width 0.1)
				(type default)
			)
			(layer "F.Fab")
		)
		(fp_line
			(start -0.700024 -1.500124)
			(end -0.700024 -1.169924)
			(stroke
				(width 0.1)
				(type default)
			)
			(layer "F.Fab")
		)
		(fp_line
			(start -0.700024 -1.169924)
			(end -1.249934 -1.169924)
			(stroke
				(width 0.1)
				(type default)
			)
			(layer "F.Fab")
		)
		(fp_line
			(start -0.700024 1.169924)
			(end -0.700024 1.500124)
			(stroke
				(width 0.1)
				(type default)
			)
			(layer "F.Fab")
		)
		(fp_line
			(start -0.700024 1.500124)
			(end 0.700024 1.500124)
			(stroke
				(width 0.1)
				(type default)
			)
			(layer "F.Fab")
		)
		(fp_line
			(start -0.6985 -0.729996)
			(end -0.6985 0.729996)
			(stroke
				(width 0.1)
				(type default)
			)
			(layer "F.Fab")
		)
		(fp_line
			(start -0.6985 0.729996)
			(end -1.249934 0.729996)
			(stroke
				(width 0.1)
				(type default)
			)
			(layer "F.Fab")
		)
		(fp_line
			(start 0.700024 -1.500124)
			(end -0.700024 -1.500124)
			(stroke
				(width 0.1)
				(type default)
			)
			(layer "F.Fab")
		)
		(fp_line
			(start 0.700024 -0.219964)
			(end 0.700024 -1.500124)
			(stroke
				(width 0.1)
				(type default)
			)
			(layer "F.Fab")
		)
		(fp_line
			(start 0.700024 0.219964)
			(end 1.249934 0.219964)
			(stroke
				(width 0.1)
				(type default)
			)
			(layer "F.Fab")
		)
		(fp_line
			(start 0.700024 1.500124)
			(end 0.700024 0.219964)
			(stroke
				(width 0.1)
				(type default)
			)
			(layer "F.Fab")
		)
		(fp_line
			(start 1.249934 -0.219964)
			(end 0.700024 -0.219964)
			(stroke
				(width 0.1)
				(type default)
			)
			(layer "F.Fab")
		)
		(fp_line
			(start 1.249934 0.219964)
			(end 1.249934 -0.219964)
			(stroke
				(width 0.1)
				(type default)
			)
			(layer "F.Fab")
		)
		(fp_rect
			(start -0.700024 1.500124)
			(end 0.700024 -1.500124)
			(stroke
				(width 0)
				(type default)
			)
			(fill no)
			(layer "F.Fab")
		)
		(pad "D" smd rect
			(at 0.999998 0 270)
			(size 0.8128 0.9144)
			(layers "F.Cu" "F.Mask" "F.Paste")
			(net "P12V_AUX_BLEEDING")
		)
		(pad "G" smd rect
			(at -0.999998 -0.94996 270)
			(size 0.8128 0.9144)
			(layers "F.Cu" "F.Mask" "F.Paste")
			(net "FM_P12V_HSC_EN_R_N")
		)
		(pad "S" smd rect
			(at -0.999998 0.94996 270)
			(size 0.8128 0.9144)
			(layers "F.Cu" "F.Mask" "F.Paste")
			(net "GND")
		)
	)
	(footprint ""
		(layer "F.Cu")
		(at 208.894426 -108.545376 180)
		(property "Reference" "R6046"
			(at 0 0 180)
			(layer "F.SilkS")
			(hide yes)
			(effects
				(font
					(size 1.27 1.27)
				)
			)
		)
		(property "Value" ""
			(at 0 0 180)
			(layer "F.Fab")
			(effects
				(font
					(size 1.27 1.27)
				)
			)
		)
		(duplicate_pad_numbers_are_jumpers no)
		(fp_line
			(start 0.7874 0.4064)
			(end -0.7874 0.4064)
			(stroke
				(width 0.1524)
				(type default)
			)
			(layer "F.SilkS")
		)
		(fp_line
			(start 0.7874 -0.4064)
			(end 0.7874 0.4064)
			(stroke
				(width 0.1524)
				(type default)
			)
			(layer "F.SilkS")
		)
		(fp_line
			(start -0.7874 0.4064)
			(end -0.7874 -0.4064)
			(stroke
				(width 0.1524)
				(type default)
			)
			(layer "F.SilkS")
		)
		(fp_line
			(start -0.7874 -0.4064)
			(end 0.7874 -0.4064)
			(stroke
				(width 0.1524)
				(type default)
			)
			(layer "F.SilkS")
		)
		(fp_line
			(start 0.67945 0.3048)
			(end 0.120396 0.3048)
			(stroke
				(width 0.1)
				(type default)
			)
			(layer "F.Fab")
		)
		(fp_line
			(start 0.67945 -0.3048)
			(end 0.67945 0.3048)
			(stroke
				(width 0.1)
				(type default)
			)
			(layer "F.Fab")
		)
		(fp_line
			(start 0.12065 -0.2794)
			(end 0.12065 -0.3048)
			(stroke
				(width 0.1)
				(type default)
			)
			(layer "F.Fab")
		)
		(fp_line
			(start 0.12065 -0.3048)
			(end 0.67945 -0.3048)
			(stroke
				(width 0.1)
				(type default)
			)
			(layer "F.Fab")
		)
		(fp_line
			(start 0.120396 0.3048)
			(end 0.120396 0.2794)
			(stroke
				(width 0.1)
				(type default)
			)
			(layer "F.Fab")
		)
		(fp_line
			(start 0.120396 0.2794)
			(end -0.12065 0.2794)
			(stroke
				(width 0.1)
				(type default)
			)
			(layer "F.Fab")
		)
		(fp_line
			(start -0.12065 0.3048)
			(end -0.67945 0.3048)
			(stroke
				(width 0.1)
				(type default)
			)
			(layer "F.Fab")
		)
		(fp_line
			(start -0.12065 0.2794)
			(end -0.12065 0.3048)
			(stroke
				(width 0.1)
				(type default)
			)
			(layer "F.Fab")
		)
		(fp_line
			(start -0.12065 -0.2794)
			(end 0.12065 -0.2794)
			(stroke
				(width 0.1)
				(type default)
			)
			(layer "F.Fab")
		)
		(fp_line
			(start -0.12065 -0.305054)
			(end -0.12065 -0.2794)
			(stroke
				(width 0.1)
				(type default)
			)
			(layer "F.Fab")
		)
		(fp_line
			(start -0.67945 0.3048)
			(end -0.67945 -0.305054)
			(stroke
				(width 0.1)
				(type default)
			)
			(layer "F.Fab")
		)
		(fp_line
			(start -0.67945 -0.305054)
			(end -0.12065 -0.305054)
			(stroke
				(width 0.1)
				(type default)
			)
			(layer "F.Fab")
		)
		(pad "1" smd circle
			(at -0.40005 0 180)
			(size 0 0)
			(layers "F.Cu" "F.Mask" "F.Paste")
			(net "HP_LVC3_OCP_SFF_PRSNT2_PLD_N")
		)
		(pad "2" smd circle
			(at 0.40005 0 180)
			(size 0 0)
			(layers "F.Cu" "F.Mask" "F.Paste")
			(net "PRSNT_OCP_SFF_N")
		)
	)
	(footprint ""
		(layer "F.Cu")
		(at 305.082448 -149.210522 180)
		(property "Reference" "R5015"
			(at 0 0 180)
			(layer "F.SilkS")
			(hide yes)
			(effects
				(font
					(size 1.27 1.27)
				)
			)
		)
		(property "Value" ""
			(at 0 0 180)
			(layer "F.Fab")
			(effects
				(font
					(size 1.27 1.27)
				)
			)
		)
		(duplicate_pad_numbers_are_jumpers no)
		(fp_line
			(start 0.7874 0.4064)
			(end -0.7874 0.4064)
			(stroke
				(width 0.1524)
				(type default)
			)
			(layer "F.SilkS")
		)
		(fp_line
			(start 0.7874 -0.4064)
			(end 0.7874 0.4064)
			(stroke
				(width 0.1524)
				(type default)
			)
			(layer "F.SilkS")
		)
		(fp_line
			(start -0.7874 0.4064)
			(end -0.7874 -0.4064)
			(stroke
				(width 0.1524)
				(type default)
			)
			(layer "F.SilkS")
		)
		(fp_line
			(start -0.7874 -0.4064)
			(end 0.7874 -0.4064)
			(stroke
				(width 0.1524)
				(type default)
			)
			(layer "F.SilkS")
		)
		(fp_line
			(start 0.67945 0.3048)
			(end 0.120396 0.3048)
			(stroke
				(width 0.1)
				(type default)
			)
			(layer "F.Fab")
		)
		(fp_line
			(start 0.67945 -0.3048)
			(end 0.67945 0.3048)
			(stroke
				(width 0.1)
				(type default)
			)
			(layer "F.Fab")
		)
		(fp_line
			(start 0.12065 -0.2794)
			(end 0.12065 -0.3048)
			(stroke
				(width 0.1)
				(type default)
			)
			(layer "F.Fab")
		)
		(fp_line
			(start 0.12065 -0.3048)
			(end 0.67945 -0.3048)
			(stroke
				(width 0.1)
				(type default)
			)
			(layer "F.Fab")
		)
		(fp_line
			(start 0.120396 0.3048)
			(end 0.120396 0.2794)
			(stroke
				(width 0.1)
				(type default)
			)
			(layer "F.Fab")
		)
		(fp_line
			(start 0.120396 0.2794)
			(end -0.12065 0.2794)
			(stroke
				(width 0.1)
				(type default)
			)
			(layer "F.Fab")
		)
		(fp_line
			(start -0.12065 0.3048)
			(end -0.67945 0.3048)
			(stroke
				(width 0.1)
				(type default)
			)
			(layer "F.Fab")
		)
		(fp_line
			(start -0.12065 0.2794)
			(end -0.12065 0.3048)
			(stroke
				(width 0.1)
				(type default)
			)
			(layer "F.Fab")
		)
		(fp_line
			(start -0.12065 -0.2794)
			(end 0.12065 -0.2794)
			(stroke
				(width 0.1)
				(type default)
			)
			(layer "F.Fab")
		)
		(fp_line
			(start -0.12065 -0.305054)
			(end -0.12065 -0.2794)
			(stroke
				(width 0.1)
				(type default)
			)
			(layer "F.Fab")
		)
		(fp_line
			(start -0.67945 0.3048)
			(end -0.67945 -0.305054)
			(stroke
				(width 0.1)
				(type default)
			)
			(layer "F.Fab")
		)
		(fp_line
			(start -0.67945 -0.305054)
			(end -0.12065 -0.305054)
			(stroke
				(width 0.1)
				(type default)
			)
			(layer "F.Fab")
		)
		(pad "1" smd circle
			(at -0.40005 0 180)
			(size 0 0)
			(layers "F.Cu" "F.Mask" "F.Paste")
			(net "PVDD11_S3_P0")
		)
		(pad "2" smd circle
			(at 0.40005 0 180)
			(size 0 0)
			(layers "F.Cu" "F.Mask" "F.Paste")
			(net "I3C_SCM_0_R_SDA")
		)
	)
	(footprint ""
		(layer "F.Cu")
		(at 399.362168 -322.930012 180)
		(property "Reference" "R465"
			(at 0 0 180)
			(layer "F.SilkS")
			(hide yes)
			(effects
				(font
					(size 1.27 1.27)
				)
			)
		)
		(property "Value" ""
			(at 0 0 180)
			(layer "F.Fab")
			(effects
				(font
					(size 1.27 1.27)
				)
			)
		)
		(duplicate_pad_numbers_are_jumpers no)
		(fp_line
			(start 0.7874 0.4064)
			(end -0.7874 0.4064)
			(stroke
				(width 0.1524)
				(type default)
			)
			(layer "F.SilkS")
		)
		(fp_line
			(start 0.7874 -0.4064)
			(end 0.7874 0.4064)
			(stroke
				(width 0.1524)
				(type default)
			)
			(layer "F.SilkS")
		)
		(fp_line
			(start -0.7874 0.4064)
			(end -0.7874 -0.4064)
			(stroke
				(width 0.1524)
				(type default)
			)
			(layer "F.SilkS")
		)
		(fp_line
			(start -0.7874 -0.4064)
			(end 0.7874 -0.4064)
			(stroke
				(width 0.1524)
				(type default)
			)
			(layer "F.SilkS")
		)
		(fp_line
			(start 0.67945 0.3048)
			(end 0.120396 0.3048)
			(stroke
				(width 0.1)
				(type default)
			)
			(layer "F.Fab")
		)
		(fp_line
			(start 0.67945 -0.3048)
			(end 0.67945 0.3048)
			(stroke
				(width 0.1)
				(type default)
			)
			(layer "F.Fab")
		)
		(fp_line
			(start 0.12065 -0.2794)
			(end 0.12065 -0.3048)
			(stroke
				(width 0.1)
				(type default)
			)
			(layer "F.Fab")
		)
		(fp_line
			(start 0.12065 -0.3048)
			(end 0.67945 -0.3048)
			(stroke
				(width 0.1)
				(type default)
			)
			(layer "F.Fab")
		)
		(fp_line
			(start 0.120396 0.3048)
			(end 0.120396 0.2794)
			(stroke
				(width 0.1)
				(type default)
			)
			(layer "F.Fab")
		)
		(fp_line
			(start 0.120396 0.2794)
			(end -0.12065 0.2794)
			(stroke
				(width 0.1)
				(type default)
			)
			(layer "F.Fab")
		)
		(fp_line
			(start -0.12065 0.3048)
			(end -0.67945 0.3048)
			(stroke
				(width 0.1)
				(type default)
			)
			(layer "F.Fab")
		)
		(fp_line
			(start -0.12065 0.2794)
			(end -0.12065 0.3048)
			(stroke
				(width 0.1)
				(type default)
			)
			(layer "F.Fab")
		)
		(fp_line
			(start -0.12065 -0.2794)
			(end 0.12065 -0.2794)
			(stroke
				(width 0.1)
				(type default)
			)
			(layer "F.Fab")
		)
		(fp_line
			(start -0.12065 -0.305054)
			(end -0.12065 -0.2794)
			(stroke
				(width 0.1)
				(type default)
			)
			(layer "F.Fab")
		)
		(fp_line
			(start -0.67945 0.3048)
			(end -0.67945 -0.305054)
			(stroke
				(width 0.1)
				(type default)
			)
			(layer "F.Fab")
		)
		(fp_line
			(start -0.67945 -0.305054)
			(end -0.12065 -0.305054)
			(stroke
				(width 0.1)
				(type default)
			)
			(layer "F.Fab")
		)
		(pad "1" smd circle
			(at -0.40005 0 180)
			(size 0 0)
			(layers "F.Cu" "F.Mask" "F.Paste")
			(net "SPI_CPU0_D1")
		)
		(pad "2" smd circle
			(at 0.40005 0 180)
			(size 0 0)
			(layers "F.Cu" "F.Mask" "F.Paste")
			(net "SPI_CPU0_R_D1")
		)
	)
	(footprint ""
		(layer "F.Cu")
		(at 353.900232 -256.505202)
		(property "Reference" "C3897"
			(at 0 0 0)
			(layer "F.SilkS")
			(hide yes)
			(effects
				(font
					(size 1.27 1.27)
				)
			)
		)
		(property "Value" ""
			(at 0 0 0)
			(layer "F.Fab")
			(effects
				(font
					(size 1.27 1.27)
				)
			)
		)
		(duplicate_pad_numbers_are_jumpers no)
		(fp_line
			(start -0.7874 -0.4064)
			(end 0.7874 -0.4064)
			(stroke
				(width 0.1524)
				(type default)
			)
			(layer "F.SilkS")
		)
		(fp_line
			(start -0.7874 0.4064)
			(end -0.7874 -0.4064)
			(stroke
				(width 0.1524)
				(type default)
			)
			(layer "F.SilkS")
		)
		(fp_line
			(start 0.7874 -0.4064)
			(end 0.7874 0.4064)
			(stroke
				(width 0.1524)
				(type default)
			)
			(layer "F.SilkS")
		)
		(fp_line
			(start 0.7874 0.4064)
			(end -0.7874 0.4064)
			(stroke
				(width 0.1524)
				(type default)
			)
			(layer "F.SilkS")
		)
		(fp_line
			(start -0.67945 -0.305054)
			(end -0.12065 -0.305054)
			(stroke
				(width 0.1)
				(type default)
			)
			(layer "F.Fab")
		)
		(fp_line
			(start -0.67945 0.3048)
			(end -0.67945 -0.305054)
			(stroke
				(width 0.1)
				(type default)
			)
			(layer "F.Fab")
		)
		(fp_line
			(start -0.12065 -0.305054)
			(end -0.12065 -0.2794)
			(stroke
				(width 0.1)
				(type default)
			)
			(layer "F.Fab")
		)
		(fp_line
			(start -0.12065 -0.2794)
			(end 0.12065 -0.2794)
			(stroke
				(width 0.1)
				(type default)
			)
			(layer "F.Fab")
		)
		(fp_line
			(start -0.12065 0.2794)
			(end -0.12065 0.3048)
			(stroke
				(width 0.1)
				(type default)
			)
			(layer "F.Fab")
		)
		(fp_line
			(start -0.12065 0.3048)
			(end -0.67945 0.3048)
			(stroke
				(width 0.1)
				(type default)
			)
			(layer "F.Fab")
		)
		(fp_line
			(start 0.120396 0.2794)
			(end -0.12065 0.2794)
			(stroke
				(width 0.1)
				(type default)
			)
			(layer "F.Fab")
		)
		(fp_line
			(start 0.120396 0.3048)
			(end 0.120396 0.2794)
			(stroke
				(width 0.1)
				(type default)
			)
			(layer "F.Fab")
		)
		(fp_line
			(start 0.12065 -0.3048)
			(end 0.67945 -0.3048)
			(stroke
				(width 0.1)
				(type default)
			)
			(layer "F.Fab")
		)
		(fp_line
			(start 0.12065 -0.2794)
			(end 0.12065 -0.3048)
			(stroke
				(width 0.1)
				(type default)
			)
			(layer "F.Fab")
		)
		(fp_line
			(start 0.67945 -0.3048)
			(end 0.67945 0.3048)
			(stroke
				(width 0.1)
				(type default)
			)
			(layer "F.Fab")
		)
		(fp_line
			(start 0.67945 0.3048)
			(end 0.120396 0.3048)
			(stroke
				(width 0.1)
				(type default)
			)
			(layer "F.Fab")
		)
		(pad "1" smd circle
			(at -0.40005 0)
			(size 0 0)
			(layers "F.Cu" "F.Mask" "F.Paste")
			(net "PVDD18_S5_P0")
		)
		(pad "2" smd circle
			(at 0.40005 0)
			(size 0 0)
			(layers "F.Cu" "F.Mask" "F.Paste")
			(net "GND")
		)
	)
)
